(kicad_pcb
	(version 20260206)
	(generator "pcbnew")
	(generator_version "10.0")
	(general
		(thickness 1.6)
		(legacy_teardrops no)
	)
	(paper "A4")
	(title_block
		(title "Bryce Canyon_SCC_16316-1_OCP.brd")
		(comment 1 "Bryce Canyon / footprints 1144-1150 of 1561")
	)
	(layers
		(0 "F.Cu" signal "TOP")
		(4 "In1.Cu" signal "L2GND")
		(6 "In2.Cu" signal "L3")
		(8 "In3.Cu" signal "L4VCC")
		(10 "In4.Cu" signal "L5VCC")
		(12 "In5.Cu" signal "L6")
		(14 "In6.Cu" signal "L7GND")
		(2 "B.Cu" signal "BOTTOM")
		(9 "F.Adhes" user "F.Adhesive")
		(11 "B.Adhes" user "B.Adhesive")
		(13 "F.Paste" user "Package Geometry/Pastemask Top")
		(15 "B.Paste" user "Package Geometry/Pastemask Bottom")
		(5 "F.SilkS" user "Ref Des/Silkscreen Top")
		(7 "B.SilkS" user "Ref Des/Silkscreen Bottom")
		(1 "F.Mask" user "Board Geometry/Soldermask Top")
		(3 "B.Mask" user "Board Geometry/Soldermask Bottom")
		(17 "Dwgs.User" user "User.Drawings")
		(19 "Cmts.User" user "User.Comments")
		(21 "Eco1.User" user "User.Eco1")
		(23 "Eco2.User" user "User.Eco2")
		(25 "Edge.Cuts" user "Board Geometry/Outline")
		(27 "Margin" user)
		(31 "F.CrtYd" user "Package Geometry/Place Bound Top")
		(29 "B.CrtYd" user "Package Geometry/Place Bound Bottom")
		(35 "F.Fab" user "Ref Des/Assembly Top")
		(33 "B.Fab" user "Ref Des/Assembly Bottom")
	)
	(footprint ""
		(layer "B.Cu")
		(at 120.6246 -57.4802)
		(property "Reference" "C267"
			(at 0 0 0)
			(layer "B.SilkS")
			(hide yes)
			(effects
				(font
					(size 1.27 1.27)
				)
				(justify mirror)
			)
		)
		(property "Value" "SCD1U6D3V1KX-GP"
			(at 2.8321 -1.7399 0)
			(unlocked yes)
			(layer "B.Fab")
			(hide yes)
			(effects
				(font
					(size 1.016 1.016)
					(thickness 0.1524)
				)
				(justify mirror)
			)
		)
		(property "Device Type" "C0201H13"
			(at 2.8321 -3.2639 0)
			(unlocked yes)
			(layer "B.Fab")
			(hide yes)
			(effects
				(font
					(size 1.016 1.016)
					(thickness 0.1524)
				)
				(justify mirror)
			)
		)
		(duplicate_pad_numbers_are_jumpers no)
		(fp_rect
			(start 0.2794 0.6477)
			(end -0.2794 -0.6477)
			(stroke
				(width 0)
				(type default)
			)
			(fill no)
			(layer "B.CrtYd")
		)
		(fp_rect
			(start 0.2794 0.6477)
			(end -0.2794 -0.6477)
			(stroke
				(width 0)
				(type default)
			)
			(fill no)
			(layer "B.Fab")
		)
		(pad "1" smd custom
			(at 0 -0.2794 180)
			(size 0.0762 0.0762)
			(layers "B.Cu" "B.Mask" "B.Paste")
			(net "GB_VDDA")
			(options
				(clearance outline)
				(anchor circle)
			)
			(primitives
				(gr_poly
					(pts
						(arc
							(start 0.1524 0.127)
							(mid 0.137521 0.162921)
							(end 0.1016 0.1778)
						)
						(arc
							(start -0.1016 0.1778)
							(mid -0.137521 0.162921)
							(end -0.1524 0.127)
						)
						(arc
							(start -0.1524 -0.127)
							(mid -0.137521 -0.162921)
							(end -0.1016 -0.1778)
						)
						(arc
							(start 0.1016 -0.1778)
							(mid 0.137521 -0.162921)
							(end 0.1524 -0.127)
						)
					)
					(width 0)
					(fill yes)
				)
			)
		)
		(pad "2" smd custom
			(at 0 0.2794 180)
			(size 0.0762 0.0762)
			(layers "B.Cu" "B.Mask" "B.Paste")
			(net "GND")
			(options
				(clearance outline)
				(anchor circle)
			)
			(primitives
				(gr_poly
					(pts
						(arc
							(start 0.1524 0.127)
							(mid 0.137521 0.162921)
							(end 0.1016 0.1778)
						)
						(arc
							(start -0.1016 0.1778)
							(mid -0.137521 0.162921)
							(end -0.1524 0.127)
						)
						(arc
							(start -0.1524 -0.127)
							(mid -0.137521 -0.162921)
							(end -0.1016 -0.1778)
						)
						(arc
							(start 0.1016 -0.1778)
							(mid 0.137521 -0.162921)
							(end 0.1524 -0.127)
						)
					)
					(width 0)
					(fill yes)
				)
			)
		)
	)
	(footprint ""
		(layer "B.Cu")
		(at 64.5922 -93.091)
		(property "Reference" "R499"
			(at 0 0 0)
			(layer "B.SilkS")
			(hide yes)
			(effects
				(font
					(size 1.27 1.27)
				)
				(justify mirror)
			)
		)
		(property "Value" "2D2R3J-2-GP"
			(at 0.0254 -2.5146 0)
			(unlocked yes)
			(layer "B.Fab")
			(hide yes)
			(effects
				(font
					(size 1.016 1.016)
					(thickness 0.1524)
				)
				(justify mirror)
			)
		)
		(property "Device Type" "R603H22"
			(at 0.0254 -4.0386 0)
			(unlocked yes)
			(layer "B.Fab")
			(hide yes)
			(effects
				(font
					(size 1.016 1.016)
					(thickness 0.1524)
				)
				(justify mirror)
			)
		)
		(duplicate_pad_numbers_are_jumpers no)
		(fp_line
			(start -0.2032 0)
			(end -0.4826 0)
			(stroke
				(width 0.2032)
				(type default)
			)
			(layer "B.SilkS")
		)
		(fp_line
			(start 0.4826 0)
			(end 0.2032 0)
			(stroke
				(width 0.2032)
				(type default)
			)
			(layer "B.SilkS")
		)
		(fp_rect
			(start 0.5842 1.3335)
			(end -0.5842 -1.3335)
			(stroke
				(width 0)
				(type default)
			)
			(fill no)
			(layer "B.CrtYd")
		)
		(fp_rect
			(start 0.5842 1.3335)
			(end -0.5842 -1.3335)
			(stroke
				(width 0)
				(type default)
			)
			(fill no)
			(layer "B.Fab")
		)
		(pad "1" smd custom
			(at 0 -0.762 180)
			(size 0.2159 0.2159)
			(layers "B.Cu" "B.Mask" "B.Paste")
			(net "P12V_STBY_VDD_U10")
			(options
				(clearance outline)
				(anchor circle)
			)
			(primitives
				(gr_poly
					(pts
						(arc
							(start -0.3302 0.4318)
							(mid -0.402042 0.402042)
							(end -0.4318 0.3302)
						)
						(arc
							(start -0.4318 -0.3302)
							(mid -0.402042 -0.402042)
							(end -0.3302 -0.4318)
						)
						(arc
							(start 0.3302 -0.4318)
							(mid 0.402042 -0.402042)
							(end 0.4318 -0.3302)
						)
						(arc
							(start 0.4318 0.3302)
							(mid 0.402042 0.402042)
							(end 0.3302 0.4318)
						)
					)
					(width 0)
					(fill yes)
				)
			)
		)
		(pad "2" smd custom
			(at 0 0.762 180)
			(size 0.2159 0.2159)
			(layers "B.Cu" "B.Mask" "B.Paste")
			(net "P12V_STBY_SCC")
			(options
				(clearance outline)
				(anchor circle)
			)
			(primitives
				(gr_poly
					(pts
						(arc
							(start -0.3302 0.4318)
							(mid -0.402042 0.402042)
							(end -0.4318 0.3302)
						)
						(arc
							(start -0.4318 -0.3302)
							(mid -0.402042 -0.402042)
							(end -0.3302 -0.4318)
						)
						(arc
							(start 0.3302 -0.4318)
							(mid 0.402042 -0.402042)
							(end 0.4318 -0.3302)
						)
						(arc
							(start 0.4318 0.3302)
							(mid 0.402042 0.402042)
							(end 0.3302 0.4318)
						)
					)
					(width 0)
					(fill yes)
				)
			)
		)
	)
	(footprint ""
		(layer "B.Cu")
		(at 169.920158 -34.370772 90)
		(property "Reference" "C402"
			(at 0 0 90)
			(layer "B.SilkS")
			(hide yes)
			(effects
				(font
					(size 1.27 1.27)
				)
				(justify mirror)
			)
		)
		(property "Value" "SCD1U16V2KX-3GP"
			(at -1.1811 -2.7051 90)
			(unlocked yes)
			(layer "B.Fab")
			(hide yes)
			(effects
				(font
					(size 1.016 1.016)
					(thickness 0.1524)
				)
				(justify mirror)
			)
		)
		(property "Device Type" "C402H22"
			(at -1.1811 -4.2291 90)
			(unlocked yes)
			(layer "B.Fab")
			(hide yes)
			(effects
				(font
					(size 1.016 1.016)
					(thickness 0.1524)
				)
				(justify mirror)
			)
		)
		(duplicate_pad_numbers_are_jumpers no)
		(fp_rect
			(start 0.4318 0.9525)
			(end -0.4318 -0.9525)
			(stroke
				(width 0)
				(type default)
			)
			(fill no)
			(layer "B.CrtYd")
		)
		(fp_rect
			(start 0.4318 0.9525)
			(end -0.4318 -0.9525)
			(stroke
				(width 0)
				(type default)
			)
			(fill no)
			(layer "B.Fab")
		)
		(pad "1" smd custom
			(at 0 -0.4445 270)
			(size 0.1524 0.1524)
			(layers "B.Cu" "B.Mask" "B.Paste")
			(net "SAS0_AVDD")
			(options
				(clearance outline)
				(anchor circle)
			)
			(primitives
				(gr_poly
					(pts
						(arc
							(start 0.3048 0.2032)
							(mid 0.275042 0.275042)
							(end 0.2032 0.3048)
						)
						(arc
							(start -0.2032 0.3048)
							(mid -0.275042 0.275042)
							(end -0.3048 0.2032)
						)
						(arc
							(start -0.3048 -0.2032)
							(mid -0.275042 -0.275042)
							(end -0.2032 -0.3048)
						)
						(arc
							(start 0.2032 -0.3048)
							(mid 0.275042 -0.275042)
							(end 0.3048 -0.2032)
						)
					)
					(width 0)
					(fill yes)
				)
			)
		)
		(pad "2" smd custom
			(at 0 0.4445 270)
			(size 0.1524 0.1524)
			(layers "B.Cu" "B.Mask" "B.Paste")
			(net "GND")
			(options
				(clearance outline)
				(anchor circle)
			)
			(primitives
				(gr_poly
					(pts
						(arc
							(start 0.3048 0.2032)
							(mid 0.275042 0.275042)
							(end 0.2032 0.3048)
						)
						(arc
							(start -0.2032 0.3048)
							(mid -0.275042 0.275042)
							(end -0.3048 0.2032)
						)
						(arc
							(start -0.3048 -0.2032)
							(mid -0.275042 -0.275042)
							(end -0.2032 -0.3048)
						)
						(arc
							(start 0.2032 -0.3048)
							(mid 0.275042 -0.275042)
							(end 0.3048 -0.2032)
						)
					)
					(width 0)
					(fill yes)
				)
			)
		)
	)
	(footprint ""
		(layer "B.Cu")
		(at 180.5432 -54.9402)
		(property "Reference" "R394"
			(at 0 0 0)
			(layer "B.SilkS")
			(hide yes)
			(effects
				(font
					(size 1.27 1.27)
				)
				(justify mirror)
			)
		)
		(property "Value" "10KR2F-2-GP"
			(at -0.064008 -3.993896 0)
			(unlocked yes)
			(layer "B.Fab")
			(hide yes)
			(effects
				(font
					(size 1.016 1.016)
					(thickness 0.1524)
				)
				(justify mirror)
			)
		)
		(property "Device Type" "R402H16"
			(at -0.064008 -5.517896 0)
			(unlocked yes)
			(layer "B.Fab")
			(hide yes)
			(effects
				(font
					(size 1.016 1.016)
					(thickness 0.1524)
				)
				(justify mirror)
			)
		)
		(duplicate_pad_numbers_are_jumpers no)
		(fp_line
			(start -0.508 -0.9398)
			(end 0.508 -0.9398)
			(stroke
				(width 0.1524)
				(type default)
			)
			(layer "B.SilkS")
		)
		(fp_line
			(start 0.508 -0.9398)
			(end 0.508 0.9398)
			(stroke
				(width 0.1524)
				(type default)
			)
			(layer "B.SilkS")
		)
		(fp_rect
			(start 0.508 0.9398)
			(end -0.508 -0.9398)
			(stroke
				(width 0)
				(type default)
			)
			(fill no)
			(layer "B.CrtYd")
		)
		(fp_rect
			(start 0.508 0.9398)
			(end -0.508 -0.9398)
			(stroke
				(width 0)
				(type default)
			)
			(fill no)
			(layer "B.Fab")
		)
		(pad "1" smd custom
			(at 0 -0.4445 180)
			(size 0.1397 0.1397)
			(layers "B.Cu" "B.Mask" "B.Paste")
			(net "P1V8_C")
			(options
				(clearance outline)
				(anchor circle)
			)
			(primitives
				(gr_poly
					(pts
						(arc
							(start -0.1778 0.2794)
							(mid -0.249642 0.249642)
							(end -0.2794 0.1778)
						)
						(arc
							(start -0.2794 -0.1778)
							(mid -0.249642 -0.249642)
							(end -0.1778 -0.2794)
						)
						(arc
							(start 0.1778 -0.2794)
							(mid 0.249642 -0.249642)
							(end 0.2794 -0.1778)
						)
						(arc
							(start 0.2794 0.1778)
							(mid 0.249642 0.249642)
							(end 0.1778 0.2794)
						)
					)
					(width 0)
					(fill yes)
				)
			)
		)
		(pad "2" smd custom
			(at 0 0.4445 180)
			(size 0.1397 0.1397)
			(layers "B.Cu" "B.Mask" "B.Paste")
			(net "XM_OE_N")
			(options
				(clearance outline)
				(anchor circle)
			)
			(primitives
				(gr_poly
					(pts
						(arc
							(start -0.1778 0.2794)
							(mid -0.249642 0.249642)
							(end -0.2794 0.1778)
						)
						(arc
							(start -0.2794 -0.1778)
							(mid -0.249642 -0.249642)
							(end -0.1778 -0.2794)
						)
						(arc
							(start 0.1778 -0.2794)
							(mid 0.249642 -0.249642)
							(end 0.2794 -0.1778)
						)
						(arc
							(start 0.2794 0.1778)
							(mid 0.249642 0.249642)
							(end 0.1778 0.2794)
						)
					)
					(width 0)
					(fill yes)
				)
			)
		)
	)
	(footprint ""
		(layer "B.Cu")
		(at 107.061 -84.455 180)
		(property "Reference" "R107"
			(at 0 0 0)
			(layer "B.SilkS")
			(hide yes)
			(effects
				(font
					(size 1.27 1.27)
				)
				(justify mirror)
			)
		)
		(property "Value" "4K75R2F-1-GP"
			(at -0.064008 -3.993896 180)
			(unlocked yes)
			(layer "B.Fab")
			(hide yes)
			(effects
				(font
					(size 1.016 1.016)
					(thickness 0.1524)
				)
				(justify mirror)
			)
		)
		(property "Device Type" "R402H16"
			(at -0.064008 -5.517896 180)
			(unlocked yes)
			(layer "B.Fab")
			(hide yes)
			(effects
				(font
					(size 1.016 1.016)
					(thickness 0.1524)
				)
				(justify mirror)
			)
		)
		(duplicate_pad_numbers_are_jumpers no)
		(fp_line
			(start 0.508 -0.9398)
			(end 0.508 0.9398)
			(stroke
				(width 0.1524)
				(type default)
			)
			(layer "B.SilkS")
		)
		(fp_line
			(start -0.508 -0.9398)
			(end 0.508 -0.9398)
			(stroke
				(width 0.1524)
				(type default)
			)
			(layer "B.SilkS")
		)
		(fp_rect
			(start 0.508 0.9398)
			(end -0.508 -0.9398)
			(stroke
				(width 0)
				(type default)
			)
			(fill no)
			(layer "B.CrtYd")
		)
		(fp_rect
			(start 0.508 0.9398)
			(end -0.508 -0.9398)
			(stroke
				(width 0)
				(type default)
			)
			(fill no)
			(layer "B.Fab")
		)
		(pad "1" smd custom
			(at 0 -0.4445)
			(size 0.1397 0.1397)
			(layers "B.Cu" "B.Mask" "B.Paste")
			(net "LSI_TRST_N")
			(options
				(clearance outline)
				(anchor circle)
			)
			(primitives
				(gr_poly
					(pts
						(arc
							(start -0.1778 0.2794)
							(mid -0.249642 0.249642)
							(end -0.2794 0.1778)
						)
						(arc
							(start -0.2794 -0.1778)
							(mid -0.249642 -0.249642)
							(end -0.1778 -0.2794)
						)
						(arc
							(start 0.1778 -0.2794)
							(mid 0.249642 -0.249642)
							(end 0.2794 -0.1778)
						)
						(arc
							(start 0.2794 0.1778)
							(mid 0.249642 0.249642)
							(end 0.1778 0.2794)
						)
					)
					(width 0)
					(fill yes)
				)
			)
		)
		(pad "2" smd custom
			(at 0 0.4445)
			(size 0.1397 0.1397)
			(layers "B.Cu" "B.Mask" "B.Paste")
			(net "GND")
			(options
				(clearance outline)
				(anchor circle)
			)
			(primitives
				(gr_poly
					(pts
						(arc
							(start -0.1778 0.2794)
							(mid -0.249642 0.249642)
							(end -0.2794 0.1778)
						)
						(arc
							(start -0.2794 -0.1778)
							(mid -0.249642 -0.249642)
							(end -0.1778 -0.2794)
						)
						(arc
							(start 0.1778 -0.2794)
							(mid 0.249642 -0.249642)
							(end 0.2794 -0.1778)
						)
						(arc
							(start 0.2794 0.1778)
							(mid 0.249642 0.249642)
							(end 0.1778 0.2794)
						)
					)
					(width 0)
					(fill yes)
				)
			)
		)
	)
	(footprint ""
		(layer "B.Cu")
		(at 111.2266 -71.9074)
		(property "Reference" "C130"
			(at 0 0 0)
			(layer "B.SilkS")
			(hide yes)
			(effects
				(font
					(size 1.27 1.27)
				)
				(justify mirror)
			)
		)
		(property "Value" "SCD1U6D3V1KX-GP"
			(at 2.8321 -1.7399 0)
			(unlocked yes)
			(layer "B.Fab")
			(hide yes)
			(effects
				(font
					(size 1.016 1.016)
					(thickness 0.1524)
				)
				(justify mirror)
			)
		)
		(property "Device Type" "C0201H13"
			(at 2.8321 -3.2639 0)
			(unlocked yes)
			(layer "B.Fab")
			(hide yes)
			(effects
				(font
					(size 1.016 1.016)
					(thickness 0.1524)
				)
				(justify mirror)
			)
		)
		(duplicate_pad_numbers_are_jumpers no)
		(fp_rect
			(start 0.2794 0.6477)
			(end -0.2794 -0.6477)
			(stroke
				(width 0)
				(type default)
			)
			(fill no)
			(layer "B.CrtYd")
		)
		(fp_rect
			(start 0.2794 0.6477)
			(end -0.2794 -0.6477)
			(stroke
				(width 0)
				(type default)
			)
			(fill no)
			(layer "B.Fab")
		)
		(pad "1" smd custom
			(at 0 -0.2794 180)
			(size 0.0762 0.0762)
			(layers "B.Cu" "B.Mask" "B.Paste")
			(net "P1V8_E")
			(options
				(clearance outline)
				(anchor circle)
			)
			(primitives
				(gr_poly
					(pts
						(arc
							(start 0.1524 0.127)
							(mid 0.137521 0.162921)
							(end 0.1016 0.1778)
						)
						(arc
							(start -0.1016 0.1778)
							(mid -0.137521 0.162921)
							(end -0.1524 0.127)
						)
						(arc
							(start -0.1524 -0.127)
							(mid -0.137521 -0.162921)
							(end -0.1016 -0.1778)
						)
						(arc
							(start 0.1016 -0.1778)
							(mid 0.137521 -0.162921)
							(end 0.1524 -0.127)
						)
					)
					(width 0)
					(fill yes)
				)
			)
		)
		(pad "2" smd custom
			(at 0 0.2794 180)
			(size 0.0762 0.0762)
			(layers "B.Cu" "B.Mask" "B.Paste")
			(net "GND")
			(options
				(clearance outline)
				(anchor circle)
			)
			(primitives
				(gr_poly
					(pts
						(arc
							(start 0.1524 0.127)
							(mid 0.137521 0.162921)
							(end 0.1016 0.1778)
						)
						(arc
							(start -0.1016 0.1778)
							(mid -0.137521 0.162921)
							(end -0.1524 0.127)
						)
						(arc
							(start -0.1524 -0.127)
							(mid -0.137521 -0.162921)
							(end -0.1016 -0.1778)
						)
						(arc
							(start 0.1016 -0.1778)
							(mid 0.137521 -0.162921)
							(end 0.1524 -0.127)
						)
					)
					(width 0)
					(fill yes)
				)
			)
		)
	)
	(footprint ""
		(layer "B.Cu")
		(at 110.5916 -71.9074)
		(property "Reference" "C135"
			(at 0 0 0)
			(layer "B.SilkS")
			(hide yes)
			(effects
				(font
					(size 1.27 1.27)
				)
				(justify mirror)
			)
		)
		(property "Value" "SCD1U6D3V1KX-GP"
			(at 2.8321 -1.7399 0)
			(unlocked yes)
			(layer "B.Fab")
			(hide yes)
			(effects
				(font
					(size 1.016 1.016)
					(thickness 0.1524)
				)
				(justify mirror)
			)
		)
		(property "Device Type" "C0201H13"
			(at 2.8321 -3.2639 0)
			(unlocked yes)
			(layer "B.Fab")
			(hide yes)
			(effects
				(font
					(size 1.016 1.016)
					(thickness 0.1524)
				)
				(justify mirror)
			)
		)
		(duplicate_pad_numbers_are_jumpers no)
		(fp_rect
			(start 0.2794 0.6477)
			(end -0.2794 -0.6477)
			(stroke
				(width 0)
				(type default)
			)
			(fill no)
			(layer "B.CrtYd")
		)
		(fp_rect
			(start 0.2794 0.6477)
			(end -0.2794 -0.6477)
			(stroke
				(width 0)
				(type default)
			)
			(fill no)
			(layer "B.Fab")
		)
		(pad "1" smd custom
			(at 0 -0.2794 180)
			(size 0.0762 0.0762)
			(layers "B.Cu" "B.Mask" "B.Paste")
			(net "P1V8_E")
			(options
				(clearance outline)
				(anchor circle)
			)
			(primitives
				(gr_poly
					(pts
						(arc
							(start 0.1524 0.127)
							(mid 0.137521 0.162921)
							(end 0.1016 0.1778)
						)
						(arc
							(start -0.1016 0.1778)
							(mid -0.137521 0.162921)
							(end -0.1524 0.127)
						)
						(arc
							(start -0.1524 -0.127)
							(mid -0.137521 -0.162921)
							(end -0.1016 -0.1778)
						)
						(arc
							(start 0.1016 -0.1778)
							(mid 0.137521 -0.162921)
							(end 0.1524 -0.127)
						)
					)
					(width 0)
					(fill yes)
				)
			)
		)
		(pad "2" smd custom
			(at 0 0.2794 180)
			(size 0.0762 0.0762)
			(layers "B.Cu" "B.Mask" "B.Paste")
			(net "GND")
			(options
				(clearance outline)
				(anchor circle)
			)
			(primitives
				(gr_poly
					(pts
						(arc
							(start 0.1524 0.127)
							(mid 0.137521 0.162921)
							(end 0.1016 0.1778)
						)
						(arc
							(start -0.1016 0.1778)
							(mid -0.137521 0.162921)
							(end -0.1524 0.127)
						)
						(arc
							(start -0.1524 -0.127)
							(mid -0.137521 -0.162921)
							(end -0.1016 -0.1778)
						)
						(arc
							(start 0.1016 -0.1778)
							(mid 0.137521 -0.162921)
							(end 0.1524 -0.127)
						)
					)
					(width 0)
					(fill yes)
				)
			)
		)
	)
)
